(kicad_pcb
	(version 20260206)
	(generator "pcbnew")
	(generator_version "10.0")
	(general
		(thickness 1.6)
		(legacy_teardrops no)
	)
	(paper "A4")
	(title_block
		(title "peb — Lightning_PEB_BRD.brd")
		(comment 1 "Lightning (Wiwynn / Facebook NVMe JBOF) / footprints 1745-1751 of 2563")
	)
	(layers
		(0 "F.Cu" signal "TOP")
		(4 "In1.Cu" signal "L2GND")
		(6 "In2.Cu" signal "L3")
		(8 "In3.Cu" signal "L4VCC")
		(10 "In4.Cu" signal "L5VCC")
		(12 "In5.Cu" signal "L6")
		(14 "In6.Cu" signal "L7GND")
		(2 "B.Cu" signal "BOTTOM")
		(9 "F.Adhes" user "F.Adhesive")
		(11 "B.Adhes" user "B.Adhesive")
		(13 "F.Paste" user "Package Geometry/Pastemask Top")
		(15 "B.Paste" user "Package Geometry/Pastemask Bottom")
		(5 "F.SilkS" user "Ref Des/Silkscreen Top")
		(7 "B.SilkS" user "Ref Des/Silkscreen Bottom")
		(1 "F.Mask" user "Board Geometry/Soldermask Top")
		(3 "B.Mask" user "Board Geometry/Soldermask Bottom")
		(17 "Dwgs.User" user "User.Drawings")
		(19 "Cmts.User" user "User.Comments")
		(21 "Eco1.User" user "User.Eco1")
		(23 "Eco2.User" user "User.Eco2")
		(25 "Edge.Cuts" user "Board Geometry/Outline")
		(27 "Margin" user)
		(31 "F.CrtYd" user "Package Geometry/Place Bound Top")
		(29 "B.CrtYd" user "Package Geometry/Place Bound Bottom")
		(35 "F.Fab" user "Ref Des/Assembly Top")
		(33 "B.Fab" user "Ref Des/Assembly Bottom")
	)
	(footprint ""
		(layer "B.Cu")
		(at 51.689 -195.58 180)
		(property "Reference" "R891"
			(at 0 0 0)
			(layer "B.SilkS")
			(hide yes)
			(effects
				(font
					(size 1.27 1.27)
				)
				(justify mirror)
			)
		)
		(property "Value" "0R2J-2-GP"
			(at -0.064008 -3.993896 180)
			(unlocked yes)
			(layer "B.Fab")
			(hide yes)
			(effects
				(font
					(size 1.016 1.016)
					(thickness 0.1524)
				)
				(justify mirror)
			)
		)
		(property "Device Type" "R402H16"
			(at -0.064008 -5.517896 180)
			(unlocked yes)
			(layer "B.Fab")
			(hide yes)
			(effects
				(font
					(size 1.016 1.016)
					(thickness 0.1524)
				)
				(justify mirror)
			)
		)
		(duplicate_pad_numbers_are_jumpers no)
		(fp_line
			(start 0.508 -0.9398)
			(end 0.508 0.9398)
			(stroke
				(width 0.1524)
				(type default)
			)
			(layer "B.SilkS")
		)
		(fp_line
			(start -0.508 -0.9398)
			(end 0.508 -0.9398)
			(stroke
				(width 0.1524)
				(type default)
			)
			(layer "B.SilkS")
		)
		(fp_rect
			(start 0.508 0.9398)
			(end -0.508 -0.9398)
			(stroke
				(width 0)
				(type default)
			)
			(fill no)
			(layer "B.CrtYd")
		)
		(fp_rect
			(start 0.508 0.9398)
			(end -0.508 -0.9398)
			(stroke
				(width 0)
				(type default)
			)
			(fill no)
			(layer "B.Fab")
		)
		(pad "1" smd custom
			(at 0 -0.4445)
			(size 0.1397 0.1397)
			(layers "B.Cu" "B.Mask" "B.Paste")
			(net "BMC_I2C7_B_DBP_SCL")
			(options
				(clearance outline)
				(anchor circle)
			)
			(primitives
				(gr_poly
					(pts
						(arc
							(start -0.1778 0.2794)
							(mid -0.249642 0.249642)
							(end -0.2794 0.1778)
						)
						(arc
							(start -0.2794 -0.1778)
							(mid -0.249642 -0.249642)
							(end -0.1778 -0.2794)
						)
						(arc
							(start 0.1778 -0.2794)
							(mid 0.249642 -0.249642)
							(end 0.2794 -0.1778)
						)
						(arc
							(start 0.2794 0.1778)
							(mid 0.249642 0.249642)
							(end 0.1778 0.2794)
						)
					)
					(width 0)
					(fill yes)
				)
			)
		)
		(pad "2" smd custom
			(at 0 0.4445)
			(size 0.1397 0.1397)
			(layers "B.Cu" "B.Mask" "B.Paste")
			(net "BUF_I2C7_B_DBP_SCL")
			(options
				(clearance outline)
				(anchor circle)
			)
			(primitives
				(gr_poly
					(pts
						(arc
							(start -0.1778 0.2794)
							(mid -0.249642 0.249642)
							(end -0.2794 0.1778)
						)
						(arc
							(start -0.2794 -0.1778)
							(mid -0.249642 -0.249642)
							(end -0.1778 -0.2794)
						)
						(arc
							(start 0.1778 -0.2794)
							(mid 0.249642 -0.249642)
							(end 0.2794 -0.1778)
						)
						(arc
							(start 0.2794 0.1778)
							(mid 0.249642 0.249642)
							(end 0.1778 0.2794)
						)
					)
					(width 0)
					(fill yes)
				)
			)
		)
	)
	(footprint ""
		(layer "B.Cu")
		(at 233.6038 -60.1218)
		(property "Reference" "C598"
			(at 0 0 0)
			(layer "B.SilkS")
			(hide yes)
			(effects
				(font
					(size 1.27 1.27)
				)
				(justify mirror)
			)
		)
		(property "Value" "SCD1U16V1KX-1-GP"
			(at 2.8321 -1.7399 0)
			(unlocked yes)
			(layer "B.Fab")
			(hide yes)
			(effects
				(font
					(size 1.016 1.016)
					(thickness 0.1524)
				)
				(justify mirror)
			)
		)
		(property "Device Type" "C0201H13"
			(at 2.8321 -3.2639 0)
			(unlocked yes)
			(layer "B.Fab")
			(hide yes)
			(effects
				(font
					(size 1.016 1.016)
					(thickness 0.1524)
				)
				(justify mirror)
			)
		)
		(duplicate_pad_numbers_are_jumpers no)
		(fp_rect
			(start 0.2794 0.6477)
			(end -0.2794 -0.6477)
			(stroke
				(width 0)
				(type default)
			)
			(fill no)
			(layer "B.CrtYd")
		)
		(fp_rect
			(start 0.2794 0.6477)
			(end -0.2794 -0.6477)
			(stroke
				(width 0)
				(type default)
			)
			(fill no)
			(layer "B.Fab")
		)
		(pad "1" smd custom
			(at 0 -0.2794 180)
			(size 0.0762 0.0762)
			(layers "B.Cu" "B.Mask" "B.Paste")
			(net "DUT_AVD_PCIE")
			(options
				(clearance outline)
				(anchor circle)
			)
			(primitives
				(gr_poly
					(pts
						(arc
							(start 0.1524 0.127)
							(mid 0.137521 0.162921)
							(end 0.1016 0.1778)
						)
						(arc
							(start -0.1016 0.1778)
							(mid -0.137521 0.162921)
							(end -0.1524 0.127)
						)
						(arc
							(start -0.1524 -0.127)
							(mid -0.137521 -0.162921)
							(end -0.1016 -0.1778)
						)
						(arc
							(start 0.1016 -0.1778)
							(mid 0.137521 -0.162921)
							(end 0.1524 -0.127)
						)
					)
					(width 0)
					(fill yes)
				)
			)
		)
		(pad "2" smd custom
			(at 0 0.2794 180)
			(size 0.0762 0.0762)
			(layers "B.Cu" "B.Mask" "B.Paste")
			(net "GND")
			(options
				(clearance outline)
				(anchor circle)
			)
			(primitives
				(gr_poly
					(pts
						(arc
							(start 0.1524 0.127)
							(mid 0.137521 0.162921)
							(end 0.1016 0.1778)
						)
						(arc
							(start -0.1016 0.1778)
							(mid -0.137521 0.162921)
							(end -0.1524 0.127)
						)
						(arc
							(start -0.1524 -0.127)
							(mid -0.137521 -0.162921)
							(end -0.1016 -0.1778)
						)
						(arc
							(start 0.1016 -0.1778)
							(mid 0.137521 -0.162921)
							(end 0.1524 -0.127)
						)
					)
					(width 0)
					(fill yes)
				)
			)
		)
	)
	(footprint ""
		(layer "B.Cu")
		(at 40.856154 -158.987744 180)
		(property "Reference" "C181"
			(at 0 0 0)
			(layer "B.SilkS")
			(hide yes)
			(effects
				(font
					(size 1.27 1.27)
				)
				(justify mirror)
			)
		)
		(property "Value" "SCD1U16V2KX-3GP"
			(at -1.1811 -2.7051 180)
			(unlocked yes)
			(layer "B.Fab")
			(hide yes)
			(effects
				(font
					(size 1.016 1.016)
					(thickness 0.1524)
				)
				(justify mirror)
			)
		)
		(property "Device Type" "C402H22"
			(at -1.1811 -4.2291 180)
			(unlocked yes)
			(layer "B.Fab")
			(hide yes)
			(effects
				(font
					(size 1.016 1.016)
					(thickness 0.1524)
				)
				(justify mirror)
			)
		)
		(duplicate_pad_numbers_are_jumpers no)
		(fp_rect
			(start 0.4318 0.9525)
			(end -0.4318 -0.9525)
			(stroke
				(width 0)
				(type default)
			)
			(fill no)
			(layer "B.CrtYd")
		)
		(fp_rect
			(start 0.4318 0.9525)
			(end -0.4318 -0.9525)
			(stroke
				(width 0)
				(type default)
			)
			(fill no)
			(layer "B.Fab")
		)
		(pad "1" smd custom
			(at 0 -0.4445)
			(size 0.1524 0.1524)
			(layers "B.Cu" "B.Mask" "B.Paste")
			(net "P1V53_STBY")
			(options
				(clearance outline)
				(anchor circle)
			)
			(primitives
				(gr_poly
					(pts
						(arc
							(start 0.3048 0.2032)
							(mid 0.275042 0.275042)
							(end 0.2032 0.3048)
						)
						(arc
							(start -0.2032 0.3048)
							(mid -0.275042 0.275042)
							(end -0.3048 0.2032)
						)
						(arc
							(start -0.3048 -0.2032)
							(mid -0.275042 -0.275042)
							(end -0.2032 -0.3048)
						)
						(arc
							(start 0.2032 -0.3048)
							(mid 0.275042 -0.275042)
							(end 0.3048 -0.2032)
						)
					)
					(width 0)
					(fill yes)
				)
			)
		)
		(pad "2" smd custom
			(at 0 0.4445)
			(size 0.1524 0.1524)
			(layers "B.Cu" "B.Mask" "B.Paste")
			(net "GND")
			(options
				(clearance outline)
				(anchor circle)
			)
			(primitives
				(gr_poly
					(pts
						(arc
							(start 0.3048 0.2032)
							(mid 0.275042 0.275042)
							(end 0.2032 0.3048)
						)
						(arc
							(start -0.2032 0.3048)
							(mid -0.275042 0.275042)
							(end -0.3048 0.2032)
						)
						(arc
							(start -0.3048 -0.2032)
							(mid -0.275042 -0.275042)
							(end -0.2032 -0.3048)
						)
						(arc
							(start 0.2032 -0.3048)
							(mid 0.275042 -0.275042)
							(end 0.3048 -0.2032)
						)
					)
					(width 0)
					(fill yes)
				)
			)
		)
	)
	(footprint ""
		(layer "B.Cu")
		(at 18.415 -132.715 90)
		(property "Reference" "R264"
			(at 0 0 90)
			(layer "B.SilkS")
			(hide yes)
			(effects
				(font
					(size 1.27 1.27)
				)
				(justify mirror)
			)
		)
		(property "Value" "2K2R2J-2-GP"
			(at -0.064008 -3.993896 90)
			(unlocked yes)
			(layer "B.Fab")
			(hide yes)
			(effects
				(font
					(size 1.016 1.016)
					(thickness 0.1524)
				)
				(justify mirror)
			)
		)
		(property "Device Type" "R402H16"
			(at -0.064008 -5.517896 90)
			(unlocked yes)
			(layer "B.Fab")
			(hide yes)
			(effects
				(font
					(size 1.016 1.016)
					(thickness 0.1524)
				)
				(justify mirror)
			)
		)
		(duplicate_pad_numbers_are_jumpers no)
		(fp_line
			(start 0.508 -0.9398)
			(end 0.508 0.9398)
			(stroke
				(width 0.1524)
				(type default)
			)
			(layer "B.SilkS")
		)
		(fp_line
			(start -0.508 -0.9398)
			(end 0.508 -0.9398)
			(stroke
				(width 0.1524)
				(type default)
			)
			(layer "B.SilkS")
		)
		(fp_rect
			(start 0.508 0.9398)
			(end -0.508 -0.9398)
			(stroke
				(width 0)
				(type default)
			)
			(fill no)
			(layer "B.CrtYd")
		)
		(fp_rect
			(start 0.508 0.9398)
			(end -0.508 -0.9398)
			(stroke
				(width 0)
				(type default)
			)
			(fill no)
			(layer "B.Fab")
		)
		(pad "1" smd custom
			(at 0 -0.4445 270)
			(size 0.1397 0.1397)
			(layers "B.Cu" "B.Mask" "B.Paste")
			(net "P3V3_STBY")
			(options
				(clearance outline)
				(anchor circle)
			)
			(primitives
				(gr_poly
					(pts
						(arc
							(start -0.1778 0.2794)
							(mid -0.249642 0.249642)
							(end -0.2794 0.1778)
						)
						(arc
							(start -0.2794 -0.1778)
							(mid -0.249642 -0.249642)
							(end -0.1778 -0.2794)
						)
						(arc
							(start 0.1778 -0.2794)
							(mid 0.249642 -0.249642)
							(end 0.2794 -0.1778)
						)
						(arc
							(start 0.2794 0.1778)
							(mid 0.249642 0.249642)
							(end 0.1778 0.2794)
						)
					)
					(width 0)
					(fill yes)
				)
			)
		)
		(pad "2" smd custom
			(at 0 0.4445 270)
			(size 0.1397 0.1397)
			(layers "B.Cu" "B.Mask" "B.Paste")
			(net "FLA_CS1_R")
			(options
				(clearance outline)
				(anchor circle)
			)
			(primitives
				(gr_poly
					(pts
						(arc
							(start -0.1778 0.2794)
							(mid -0.249642 0.249642)
							(end -0.2794 0.1778)
						)
						(arc
							(start -0.2794 -0.1778)
							(mid -0.249642 -0.249642)
							(end -0.1778 -0.2794)
						)
						(arc
							(start 0.1778 -0.2794)
							(mid 0.249642 -0.249642)
							(end 0.2794 -0.1778)
						)
						(arc
							(start 0.2794 0.1778)
							(mid 0.249642 0.249642)
							(end 0.1778 0.2794)
						)
					)
					(width 0)
					(fill yes)
				)
			)
		)
	)
	(footprint ""
		(layer "B.Cu")
		(at 127.103124 -208.889092 180)
		(property "Reference" "R4133"
			(at 0 0 0)
			(layer "B.SilkS")
			(hide yes)
			(effects
				(font
					(size 1.27 1.27)
				)
				(justify mirror)
			)
		)
		(property "Value" "4K7R2F-GP"
			(at -0.064008 -3.993896 180)
			(unlocked yes)
			(layer "B.Fab")
			(hide yes)
			(effects
				(font
					(size 1.016 1.016)
					(thickness 0.1524)
				)
				(justify mirror)
			)
		)
		(property "Device Type" "R402H16"
			(at -0.064008 -5.517896 180)
			(unlocked yes)
			(layer "B.Fab")
			(hide yes)
			(effects
				(font
					(size 1.016 1.016)
					(thickness 0.1524)
				)
				(justify mirror)
			)
		)
		(duplicate_pad_numbers_are_jumpers no)
		(fp_line
			(start 0.508 -0.9398)
			(end 0.508 0.9398)
			(stroke
				(width 0.1524)
				(type default)
			)
			(layer "B.SilkS")
		)
		(fp_line
			(start -0.508 -0.9398)
			(end 0.508 -0.9398)
			(stroke
				(width 0.1524)
				(type default)
			)
			(layer "B.SilkS")
		)
		(fp_rect
			(start 0.508 0.9398)
			(end -0.508 -0.9398)
			(stroke
				(width 0)
				(type default)
			)
			(fill no)
			(layer "B.CrtYd")
		)
		(fp_rect
			(start 0.508 0.9398)
			(end -0.508 -0.9398)
			(stroke
				(width 0)
				(type default)
			)
			(fill no)
			(layer "B.Fab")
		)
		(pad "1" smd custom
			(at 0 -0.4445)
			(size 0.1397 0.1397)
			(layers "B.Cu" "B.Mask" "B.Paste")
			(net "SSD_PERST#7")
			(options
				(clearance outline)
				(anchor circle)
			)
			(primitives
				(gr_poly
					(pts
						(arc
							(start -0.1778 0.2794)
							(mid -0.249642 0.249642)
							(end -0.2794 0.1778)
						)
						(arc
							(start -0.2794 -0.1778)
							(mid -0.249642 -0.249642)
							(end -0.1778 -0.2794)
						)
						(arc
							(start 0.1778 -0.2794)
							(mid 0.249642 -0.249642)
							(end 0.2794 -0.1778)
						)
						(arc
							(start 0.2794 0.1778)
							(mid 0.249642 0.249642)
							(end 0.1778 0.2794)
						)
					)
					(width 0)
					(fill yes)
				)
			)
		)
		(pad "2" smd custom
			(at 0 0.4445)
			(size 0.1397 0.1397)
			(layers "B.Cu" "B.Mask" "B.Paste")
			(net "P3V3_STBY")
			(options
				(clearance outline)
				(anchor circle)
			)
			(primitives
				(gr_poly
					(pts
						(arc
							(start -0.1778 0.2794)
							(mid -0.249642 0.249642)
							(end -0.2794 0.1778)
						)
						(arc
							(start -0.2794 -0.1778)
							(mid -0.249642 -0.249642)
							(end -0.1778 -0.2794)
						)
						(arc
							(start 0.1778 -0.2794)
							(mid 0.249642 -0.249642)
							(end 0.2794 -0.1778)
						)
						(arc
							(start 0.2794 0.1778)
							(mid 0.249642 0.249642)
							(end 0.1778 0.2794)
						)
					)
					(width 0)
					(fill yes)
				)
			)
		)
	)
	(footprint ""
		(layer "B.Cu")
		(at 322.537836 -36.991036 180)
		(property "Reference" "C237"
			(at 0 0 0)
			(layer "B.SilkS")
			(hide yes)
			(effects
				(font
					(size 1.27 1.27)
				)
				(justify mirror)
			)
		)
		(property "Value" "SCD1U10V2KX-5GP"
			(at -1.1811 -2.7051 180)
			(unlocked yes)
			(layer "B.Fab")
			(hide yes)
			(effects
				(font
					(size 1.016 1.016)
					(thickness 0.1524)
				)
				(justify mirror)
			)
		)
		(property "Device Type" "C402H22"
			(at -1.1811 -4.2291 180)
			(unlocked yes)
			(layer "B.Fab")
			(hide yes)
			(effects
				(font
					(size 1.016 1.016)
					(thickness 0.1524)
				)
				(justify mirror)
			)
		)
		(duplicate_pad_numbers_are_jumpers no)
		(fp_rect
			(start 0.4318 0.9525)
			(end -0.4318 -0.9525)
			(stroke
				(width 0)
				(type default)
			)
			(fill no)
			(layer "B.CrtYd")
		)
		(fp_rect
			(start 0.4318 0.9525)
			(end -0.4318 -0.9525)
			(stroke
				(width 0)
				(type default)
			)
			(fill no)
			(layer "B.Fab")
		)
		(pad "1" smd custom
			(at 0 -0.4445)
			(size 0.1524 0.1524)
			(layers "B.Cu" "B.Mask" "B.Paste")
			(net "GND")
			(options
				(clearance outline)
				(anchor circle)
			)
			(primitives
				(gr_poly
					(pts
						(arc
							(start 0.3048 0.2032)
							(mid 0.275042 0.275042)
							(end 0.2032 0.3048)
						)
						(arc
							(start -0.2032 0.3048)
							(mid -0.275042 0.275042)
							(end -0.3048 0.2032)
						)
						(arc
							(start -0.3048 -0.2032)
							(mid -0.275042 -0.275042)
							(end -0.2032 -0.3048)
						)
						(arc
							(start 0.2032 -0.3048)
							(mid 0.275042 -0.275042)
							(end 0.3048 -0.2032)
						)
					)
					(width 0)
					(fill yes)
				)
			)
		)
		(pad "2" smd custom
			(at 0 0.4445)
			(size 0.1524 0.1524)
			(layers "B.Cu" "B.Mask" "B.Paste")
			(net "P3V3_STBY")
			(options
				(clearance outline)
				(anchor circle)
			)
			(primitives
				(gr_poly
					(pts
						(arc
							(start 0.3048 0.2032)
							(mid 0.275042 0.275042)
							(end 0.2032 0.3048)
						)
						(arc
							(start -0.2032 0.3048)
							(mid -0.275042 0.275042)
							(end -0.3048 0.2032)
						)
						(arc
							(start -0.3048 -0.2032)
							(mid -0.275042 -0.275042)
							(end -0.2032 -0.3048)
						)
						(arc
							(start 0.2032 -0.3048)
							(mid 0.275042 -0.275042)
							(end 0.3048 -0.2032)
						)
					)
					(width 0)
					(fill yes)
				)
			)
		)
	)
	(footprint ""
		(layer "B.Cu")
		(at 76.848716 -183.238902)
		(property "Reference" "R4106"
			(at 0 0 0)
			(layer "B.SilkS")
			(hide yes)
			(effects
				(font
					(size 1.27 1.27)
				)
				(justify mirror)
			)
		)
		(property "Value" "4K7R2F-GP"
			(at -0.064008 -3.993896 0)
			(unlocked yes)
			(layer "B.Fab")
			(hide yes)
			(effects
				(font
					(size 1.016 1.016)
					(thickness 0.1524)
				)
				(justify mirror)
			)
		)
		(property "Device Type" "R402H16"
			(at -0.064008 -5.517896 0)
			(unlocked yes)
			(layer "B.Fab")
			(hide yes)
			(effects
				(font
					(size 1.016 1.016)
					(thickness 0.1524)
				)
				(justify mirror)
			)
		)
		(duplicate_pad_numbers_are_jumpers no)
		(fp_line
			(start -0.508 -0.9398)
			(end 0.508 -0.9398)
			(stroke
				(width 0.1524)
				(type default)
			)
			(layer "B.SilkS")
		)
		(fp_line
			(start 0.508 -0.9398)
			(end 0.508 0.9398)
			(stroke
				(width 0.1524)
				(type default)
			)
			(layer "B.SilkS")
		)
		(fp_rect
			(start 0.508 0.9398)
			(end -0.508 -0.9398)
			(stroke
				(width 0)
				(type default)
			)
			(fill no)
			(layer "B.CrtYd")
		)
		(fp_rect
			(start 0.508 0.9398)
			(end -0.508 -0.9398)
			(stroke
				(width 0)
				(type default)
			)
			(fill no)
			(layer "B.Fab")
		)
		(pad "1" smd custom
			(at 0 -0.4445 180)
			(size 0.1397 0.1397)
			(layers "B.Cu" "B.Mask" "B.Paste")
			(net "SSD_ATNLED#5")
			(options
				(clearance outline)
				(anchor circle)
			)
			(primitives
				(gr_poly
					(pts
						(arc
							(start -0.1778 0.2794)
							(mid -0.249642 0.249642)
							(end -0.2794 0.1778)
						)
						(arc
							(start -0.2794 -0.1778)
							(mid -0.249642 -0.249642)
							(end -0.1778 -0.2794)
						)
						(arc
							(start 0.1778 -0.2794)
							(mid 0.249642 -0.249642)
							(end 0.2794 -0.1778)
						)
						(arc
							(start 0.2794 0.1778)
							(mid 0.249642 0.249642)
							(end 0.1778 0.2794)
						)
					)
					(width 0)
					(fill yes)
				)
			)
		)
		(pad "2" smd custom
			(at 0 0.4445 180)
			(size 0.1397 0.1397)
			(layers "B.Cu" "B.Mask" "B.Paste")
			(net "P3V3_STBY")
			(options
				(clearance outline)
				(anchor circle)
			)
			(primitives
				(gr_poly
					(pts
						(arc
							(start -0.1778 0.2794)
							(mid -0.249642 0.249642)
							(end -0.2794 0.1778)
						)
						(arc
							(start -0.2794 -0.1778)
							(mid -0.249642 -0.249642)
							(end -0.1778 -0.2794)
						)
						(arc
							(start 0.1778 -0.2794)
							(mid 0.249642 -0.249642)
							(end 0.2794 -0.1778)
						)
						(arc
							(start 0.2794 0.1778)
							(mid 0.249642 0.249642)
							(end 0.1778 0.2794)
						)
					)
					(width 0)
					(fill yes)
				)
			)
		)
	)
)
